(kicad_pcb
	(version 20260206)
	(generator "pcbnew")
	(generator_version "10.0")
	(general
		(thickness 1.6)
		(legacy_teardrops no)
	)
	(paper "A4")
	(title_block
		(title "01162023_DA0F0TEBIF0_F0T_Expander_BD_F_brd_V02_OCP.brd")
		(comment 1 "Grand Teton / footprints 7223-7230 of 9728")
	)
	(layers
		(0 "F.Cu" signal "TOP")
		(4 "In1.Cu" signal "GND")
		(6 "In2.Cu" signal "VCC")
		(8 "In3.Cu" signal "VCC1")
		(10 "In4.Cu" signal "GND1")
		(12 "In5.Cu" signal "IN1")
		(14 "In6.Cu" signal "GND2")
		(16 "In7.Cu" signal "IN2")
		(18 "In8.Cu" signal "GND3")
		(20 "In9.Cu" signal "IN3")
		(22 "In10.Cu" signal "GND4")
		(24 "In11.Cu" signal "IN4")
		(26 "In12.Cu" signal "GND5")
		(28 "In13.Cu" signal "IN5")
		(30 "In14.Cu" signal "GND6")
		(32 "In15.Cu" signal "IN6")
		(34 "In16.Cu" signal "GND7")
		(2 "B.Cu" signal "BOTTOM")
		(9 "F.Adhes" user "F.Adhesive")
		(11 "B.Adhes" user "B.Adhesive")
		(13 "F.Paste" user "Package Geometry/Pastemask Top")
		(15 "B.Paste" user "Package Geometry/Pastemask Bottom")
		(5 "F.SilkS" user "Ref Des/Silkscreen Top")
		(7 "B.SilkS" user "Ref Des/Silkscreen Bottom")
		(1 "F.Mask" user "Board Geometry/Soldermask Top")
		(3 "B.Mask" user "Board Geometry/Soldermask Bottom")
		(17 "Dwgs.User" user "User.Drawings")
		(19 "Cmts.User" user "User.Comments")
		(21 "Eco1.User" user "User.Eco1")
		(23 "Eco2.User" user "User.Eco2")
		(25 "Edge.Cuts" user "Board Geometry/Outline")
		(27 "Margin" user)
		(31 "F.CrtYd" user "Package Geometry/Place Bound Top")
		(29 "B.CrtYd" user "Package Geometry/Place Bound Bottom")
		(35 "F.Fab" user "Ref Des/Assembly Top")
		(33 "B.Fab" user "Ref Des/Assembly Bottom")
	)
	(footprint ""
		(layer "B.Cu")
		(at 353.224338 -324.941946 -90)
		(property "Reference" "C4380"
			(at 0 0 90)
			(layer "B.SilkS")
			(hide yes)
			(effects
				(font
					(size 1.27 1.27)
				)
				(justify mirror)
			)
		)
		(property "Value" ""
			(at 0 0 90)
			(layer "B.Fab")
			(effects
				(font
					(size 1.27 1.27)
				)
				(justify mirror)
			)
		)
		(duplicate_pad_numbers_are_jumpers no)
		(fp_line
			(start -1.2954 0.5842)
			(end 1.2954 0.5842)
			(stroke
				(width 0.1524)
				(type default)
			)
			(layer "B.SilkS")
		)
		(fp_line
			(start 1.2954 0.5842)
			(end 1.2954 -0.5842)
			(stroke
				(width 0.1524)
				(type default)
			)
			(layer "B.SilkS")
		)
		(fp_line
			(start -1.2954 -0.5842)
			(end -1.2954 0.5842)
			(stroke
				(width 0.1524)
				(type default)
			)
			(layer "B.SilkS")
		)
		(fp_line
			(start 1.2954 -0.5842)
			(end -1.2954 -0.5842)
			(stroke
				(width 0.1524)
				(type default)
			)
			(layer "B.SilkS")
		)
		(fp_line
			(start -0.8636 0.4572)
			(end 0.8636 0.4572)
			(stroke
				(width 0.1)
				(type default)
			)
			(layer "B.Fab")
		)
		(fp_line
			(start 0.8636 0.4572)
			(end 0.8636 0.4064)
			(stroke
				(width 0.1)
				(type default)
			)
			(layer "B.Fab")
		)
		(fp_line
			(start -1.1938 0.4064)
			(end -0.8636 0.4064)
			(stroke
				(width 0.1)
				(type default)
			)
			(layer "B.Fab")
		)
		(fp_line
			(start -0.8636 0.4064)
			(end -0.8636 0.4572)
			(stroke
				(width 0.1)
				(type default)
			)
			(layer "B.Fab")
		)
		(fp_line
			(start 0.8636 0.4064)
			(end 1.1938 0.4064)
			(stroke
				(width 0.1)
				(type default)
			)
			(layer "B.Fab")
		)
		(fp_line
			(start 1.1938 0.4064)
			(end 1.1938 -0.4064)
			(stroke
				(width 0.1)
				(type default)
			)
			(layer "B.Fab")
		)
		(fp_line
			(start -1.1938 -0.4064)
			(end -1.1938 0.4064)
			(stroke
				(width 0.1)
				(type default)
			)
			(layer "B.Fab")
		)
		(fp_line
			(start -0.8636 -0.4064)
			(end -1.1938 -0.4064)
			(stroke
				(width 0.1)
				(type default)
			)
			(layer "B.Fab")
		)
		(fp_line
			(start 0.8636 -0.4064)
			(end 0.8636 -0.4572)
			(stroke
				(width 0.1)
				(type default)
			)
			(layer "B.Fab")
		)
		(fp_line
			(start 1.1938 -0.4064)
			(end 0.8636 -0.4064)
			(stroke
				(width 0.1)
				(type default)
			)
			(layer "B.Fab")
		)
		(fp_line
			(start -0.8636 -0.4572)
			(end -0.8636 -0.4064)
			(stroke
				(width 0.1)
				(type default)
			)
			(layer "B.Fab")
		)
		(fp_line
			(start 0.8636 -0.4572)
			(end -0.8636 -0.4572)
			(stroke
				(width 0.1)
				(type default)
			)
			(layer "B.Fab")
		)
		(pad "1" smd rect
			(at 0.7366 0 180)
			(size 0.7112 0.8128)
			(layers "B.Cu" "B.Mask" "B.Paste")
			(net "P0V8_SERDES_VDDA_PEX3_C6")
		)
		(pad "2" smd rect
			(at -0.7366 0 180)
			(size 0.7112 0.8128)
			(layers "B.Cu" "B.Mask" "B.Paste")
			(net "GND")
		)
	)
	(footprint ""
		(layer "B.Cu")
		(at 238.443008 -224.424494 90)
		(property "Reference" "R6818"
			(at 0 0 90)
			(layer "B.SilkS")
			(hide yes)
			(effects
				(font
					(size 1.27 1.27)
				)
				(justify mirror)
			)
		)
		(property "Value" ""
			(at 0 0 90)
			(layer "B.Fab")
			(effects
				(font
					(size 1.27 1.27)
				)
				(justify mirror)
			)
		)
		(duplicate_pad_numbers_are_jumpers no)
		(fp_line
			(start 0.7874 -0.4064)
			(end -0.7874 -0.4064)
			(stroke
				(width 0.1524)
				(type default)
			)
			(layer "B.SilkS")
		)
		(fp_line
			(start -0.7874 -0.4064)
			(end -0.7874 0.4064)
			(stroke
				(width 0.1524)
				(type default)
			)
			(layer "B.SilkS")
		)
		(fp_line
			(start 0.7874 0.4064)
			(end 0.7874 -0.4064)
			(stroke
				(width 0.1524)
				(type default)
			)
			(layer "B.SilkS")
		)
		(fp_line
			(start -0.7874 0.4064)
			(end 0.7874 0.4064)
			(stroke
				(width 0.1524)
				(type default)
			)
			(layer "B.SilkS")
		)
		(fp_line
			(start 0.67945 -0.305054)
			(end 0.12065 -0.305054)
			(stroke
				(width 0.1)
				(type default)
			)
			(layer "B.Fab")
		)
		(fp_line
			(start 0.12065 -0.305054)
			(end 0.12065 -0.2794)
			(stroke
				(width 0.1)
				(type default)
			)
			(layer "B.Fab")
		)
		(fp_line
			(start -0.12065 -0.3048)
			(end -0.67945 -0.3048)
			(stroke
				(width 0.1)
				(type default)
			)
			(layer "B.Fab")
		)
		(fp_line
			(start -0.67945 -0.3048)
			(end -0.67945 0.3048)
			(stroke
				(width 0.1)
				(type default)
			)
			(layer "B.Fab")
		)
		(fp_line
			(start 0.12065 -0.2794)
			(end -0.12065 -0.2794)
			(stroke
				(width 0.1)
				(type default)
			)
			(layer "B.Fab")
		)
		(fp_line
			(start -0.12065 -0.2794)
			(end -0.12065 -0.3048)
			(stroke
				(width 0.1)
				(type default)
			)
			(layer "B.Fab")
		)
		(fp_line
			(start 0.12065 0.2794)
			(end 0.12065 0.3048)
			(stroke
				(width 0.1)
				(type default)
			)
			(layer "B.Fab")
		)
		(fp_line
			(start -0.120396 0.2794)
			(end 0.12065 0.2794)
			(stroke
				(width 0.1)
				(type default)
			)
			(layer "B.Fab")
		)
		(fp_line
			(start 0.67945 0.3048)
			(end 0.67945 -0.305054)
			(stroke
				(width 0.1)
				(type default)
			)
			(layer "B.Fab")
		)
		(fp_line
			(start 0.12065 0.3048)
			(end 0.67945 0.3048)
			(stroke
				(width 0.1)
				(type default)
			)
			(layer "B.Fab")
		)
		(fp_line
			(start -0.120396 0.3048)
			(end -0.120396 0.2794)
			(stroke
				(width 0.1)
				(type default)
			)
			(layer "B.Fab")
		)
		(fp_line
			(start -0.67945 0.3048)
			(end -0.120396 0.3048)
			(stroke
				(width 0.1)
				(type default)
			)
			(layer "B.Fab")
		)
		(pad "1" smd circle
			(at 0.40005 0 270)
			(size 0 0)
			(layers "B.Cu" "B.Mask" "B.Paste")
			(net "GND")
		)
		(pad "2" smd circle
			(at -0.40005 0 270)
			(size 0 0)
			(layers "B.Cu" "B.Mask" "B.Paste")
			(net "VR_TYPE_ADC_R")
		)
	)
	(footprint ""
		(layer "B.Cu")
		(at 418.399976 -290.674806 180)
		(property "Reference" "C3514"
			(at 0 0 0)
			(layer "B.SilkS")
			(hide yes)
			(effects
				(font
					(size 1.27 1.27)
				)
				(justify mirror)
			)
		)
		(property "Value" ""
			(at 0 0 0)
			(layer "B.Fab")
			(effects
				(font
					(size 1.27 1.27)
				)
				(justify mirror)
			)
		)
		(duplicate_pad_numbers_are_jumpers no)
		(fp_line
			(start 0.299974 0.150114)
			(end 0.299974 -0.150114)
			(stroke
				(width 0.1)
				(type default)
			)
			(layer "B.Fab")
		)
		(fp_line
			(start 0.299974 -0.150114)
			(end -0.299974 -0.150114)
			(stroke
				(width 0.1)
				(type default)
			)
			(layer "B.Fab")
		)
		(fp_line
			(start -0.299974 0.150114)
			(end 0.299974 0.150114)
			(stroke
				(width 0.1)
				(type default)
			)
			(layer "B.Fab")
		)
		(fp_line
			(start -0.299974 -0.150114)
			(end -0.299974 0.150114)
			(stroke
				(width 0.1)
				(type default)
			)
			(layer "B.Fab")
		)
		(pad "1" smd rect
			(at 0.2667 0)
			(size 0.3048 0.381)
			(layers "B.Cu" "B.Mask" "B.Paste")
			(net "P1V8_PEX")
		)
		(pad "2" smd rect
			(at -0.2667 0)
			(size 0.3048 0.381)
			(layers "B.Cu" "B.Mask" "B.Paste")
			(net "GND")
		)
	)
	(footprint ""
		(layer "B.Cu")
		(at 115.775994 -308.580028 90)
		(property "Reference" "C1160"
			(at 0 0 90)
			(layer "B.SilkS")
			(hide yes)
			(effects
				(font
					(size 1.27 1.27)
				)
				(justify mirror)
			)
		)
		(property "Value" ""
			(at 0 0 90)
			(layer "B.Fab")
			(effects
				(font
					(size 1.27 1.27)
				)
				(justify mirror)
			)
		)
		(duplicate_pad_numbers_are_jumpers no)
		(fp_line
			(start 1.2954 -0.5842)
			(end -1.2954 -0.5842)
			(stroke
				(width 0.1524)
				(type default)
			)
			(layer "B.SilkS")
		)
		(fp_line
			(start -1.2954 -0.5842)
			(end -1.2954 0.5842)
			(stroke
				(width 0.1524)
				(type default)
			)
			(layer "B.SilkS")
		)
		(fp_line
			(start 1.2954 0.5842)
			(end 1.2954 -0.5842)
			(stroke
				(width 0.1524)
				(type default)
			)
			(layer "B.SilkS")
		)
		(fp_line
			(start -1.2954 0.5842)
			(end 1.2954 0.5842)
			(stroke
				(width 0.1524)
				(type default)
			)
			(layer "B.SilkS")
		)
		(fp_line
			(start 0.8636 -0.4572)
			(end -0.8636 -0.4572)
			(stroke
				(width 0.1)
				(type default)
			)
			(layer "B.Fab")
		)
		(fp_line
			(start -0.8636 -0.4572)
			(end -0.8636 -0.4064)
			(stroke
				(width 0.1)
				(type default)
			)
			(layer "B.Fab")
		)
		(fp_line
			(start 1.1938 -0.4064)
			(end 0.8636 -0.4064)
			(stroke
				(width 0.1)
				(type default)
			)
			(layer "B.Fab")
		)
		(fp_line
			(start 0.8636 -0.4064)
			(end 0.8636 -0.4572)
			(stroke
				(width 0.1)
				(type default)
			)
			(layer "B.Fab")
		)
		(fp_line
			(start -0.8636 -0.4064)
			(end -1.1938 -0.4064)
			(stroke
				(width 0.1)
				(type default)
			)
			(layer "B.Fab")
		)
		(fp_line
			(start -1.1938 -0.4064)
			(end -1.1938 0.4064)
			(stroke
				(width 0.1)
				(type default)
			)
			(layer "B.Fab")
		)
		(fp_line
			(start 1.1938 0.4064)
			(end 1.1938 -0.4064)
			(stroke
				(width 0.1)
				(type default)
			)
			(layer "B.Fab")
		)
		(fp_line
			(start 0.8636 0.4064)
			(end 1.1938 0.4064)
			(stroke
				(width 0.1)
				(type default)
			)
			(layer "B.Fab")
		)
		(fp_line
			(start -0.8636 0.4064)
			(end -0.8636 0.4572)
			(stroke
				(width 0.1)
				(type default)
			)
			(layer "B.Fab")
		)
		(fp_line
			(start -1.1938 0.4064)
			(end -0.8636 0.4064)
			(stroke
				(width 0.1)
				(type default)
			)
			(layer "B.Fab")
		)
		(fp_line
			(start 0.8636 0.4572)
			(end 0.8636 0.4064)
			(stroke
				(width 0.1)
				(type default)
			)
			(layer "B.Fab")
		)
		(fp_line
			(start -0.8636 0.4572)
			(end 0.8636 0.4572)
			(stroke
				(width 0.1)
				(type default)
			)
			(layer "B.Fab")
		)
		(pad "1" smd rect
			(at 0.7366 0)
			(size 0.7112 0.8128)
			(layers "B.Cu" "B.Mask" "B.Paste")
			(net "P0V8_SERDES_VDDA_PEX0")
		)
		(pad "2" smd rect
			(at -0.7366 0)
			(size 0.7112 0.8128)
			(layers "B.Cu" "B.Mask" "B.Paste")
			(net "GND")
		)
	)
	(footprint ""
		(layer "B.Cu")
		(at 51.099974 -290.199826 90)
		(property "Reference" "C1184"
			(at 0 0 90)
			(layer "B.SilkS")
			(hide yes)
			(effects
				(font
					(size 1.27 1.27)
				)
				(justify mirror)
			)
		)
		(property "Value" ""
			(at 0 0 90)
			(layer "B.Fab")
			(effects
				(font
					(size 1.27 1.27)
				)
				(justify mirror)
			)
		)
		(duplicate_pad_numbers_are_jumpers no)
		(fp_line
			(start 0.299974 -0.150114)
			(end -0.299974 -0.150114)
			(stroke
				(width 0.1)
				(type default)
			)
			(layer "B.Fab")
		)
		(fp_line
			(start -0.299974 -0.150114)
			(end -0.299974 0.150114)
			(stroke
				(width 0.1)
				(type default)
			)
			(layer "B.Fab")
		)
		(fp_line
			(start 0.299974 0.150114)
			(end 0.299974 -0.150114)
			(stroke
				(width 0.1)
				(type default)
			)
			(layer "B.Fab")
		)
		(fp_line
			(start -0.299974 0.150114)
			(end 0.299974 0.150114)
			(stroke
				(width 0.1)
				(type default)
			)
			(layer "B.Fab")
		)
		(pad "1" smd rect
			(at 0.2667 0 270)
			(size 0.3048 0.381)
			(layers "B.Cu" "B.Mask" "B.Paste")
			(net "P0V8_SERDES_VDDA_PEX0")
		)
		(pad "2" smd rect
			(at -0.2667 0 270)
			(size 0.3048 0.381)
			(layers "B.Cu" "B.Mask" "B.Paste")
			(net "GND")
		)
	)
	(footprint ""
		(layer "B.Cu")
		(at 192.923922 -114.35207 90)
		(property "Reference" "C897"
			(at 0 0 90)
			(layer "B.SilkS")
			(hide yes)
			(effects
				(font
					(size 1.27 1.27)
				)
				(justify mirror)
			)
		)
		(property "Value" ""
			(at 0 0 90)
			(layer "B.Fab")
			(effects
				(font
					(size 1.27 1.27)
				)
				(justify mirror)
			)
		)
		(duplicate_pad_numbers_are_jumpers no)
		(fp_line
			(start 0.7874 -0.4064)
			(end -0.7874 -0.4064)
			(stroke
				(width 0.1524)
				(type default)
			)
			(layer "B.SilkS")
		)
		(fp_line
			(start -0.7874 -0.4064)
			(end -0.7874 0.4064)
			(stroke
				(width 0.1524)
				(type default)
			)
			(layer "B.SilkS")
		)
		(fp_line
			(start 0.7874 0.4064)
			(end 0.7874 -0.4064)
			(stroke
				(width 0.1524)
				(type default)
			)
			(layer "B.SilkS")
		)
		(fp_line
			(start -0.7874 0.4064)
			(end 0.7874 0.4064)
			(stroke
				(width 0.1524)
				(type default)
			)
			(layer "B.SilkS")
		)
		(fp_line
			(start 0.67945 -0.305054)
			(end 0.12065 -0.305054)
			(stroke
				(width 0.1)
				(type default)
			)
			(layer "B.Fab")
		)
		(fp_line
			(start 0.12065 -0.305054)
			(end 0.12065 -0.2794)
			(stroke
				(width 0.1)
				(type default)
			)
			(layer "B.Fab")
		)
		(fp_line
			(start -0.12065 -0.3048)
			(end -0.67945 -0.3048)
			(stroke
				(width 0.1)
				(type default)
			)
			(layer "B.Fab")
		)
		(fp_line
			(start -0.67945 -0.3048)
			(end -0.67945 0.3048)
			(stroke
				(width 0.1)
				(type default)
			)
			(layer "B.Fab")
		)
		(fp_line
			(start 0.12065 -0.2794)
			(end -0.12065 -0.2794)
			(stroke
				(width 0.1)
				(type default)
			)
			(layer "B.Fab")
		)
		(fp_line
			(start -0.12065 -0.2794)
			(end -0.12065 -0.3048)
			(stroke
				(width 0.1)
				(type default)
			)
			(layer "B.Fab")
		)
		(fp_line
			(start 0.12065 0.2794)
			(end 0.12065 0.3048)
			(stroke
				(width 0.1)
				(type default)
			)
			(layer "B.Fab")
		)
		(fp_line
			(start -0.120396 0.2794)
			(end 0.12065 0.2794)
			(stroke
				(width 0.1)
				(type default)
			)
			(layer "B.Fab")
		)
		(fp_line
			(start 0.67945 0.3048)
			(end 0.67945 -0.305054)
			(stroke
				(width 0.1)
				(type default)
			)
			(layer "B.Fab")
		)
		(fp_line
			(start 0.12065 0.3048)
			(end 0.67945 0.3048)
			(stroke
				(width 0.1)
				(type default)
			)
			(layer "B.Fab")
		)
		(fp_line
			(start -0.120396 0.3048)
			(end -0.120396 0.2794)
			(stroke
				(width 0.1)
				(type default)
			)
			(layer "B.Fab")
		)
		(fp_line
			(start -0.67945 0.3048)
			(end -0.120396 0.3048)
			(stroke
				(width 0.1)
				(type default)
			)
			(layer "B.Fab")
		)
		(pad "1" smd circle
			(at 0.40005 0 270)
			(size 0 0)
			(layers "B.Cu" "B.Mask" "B.Paste")
			(net "P3V3_NIC3")
		)
		(pad "2" smd circle
			(at -0.40005 0 270)
			(size 0 0)
			(layers "B.Cu" "B.Mask" "B.Paste")
			(net "GND")
		)
	)
	(footprint ""
		(layer "B.Cu")
		(at 309.02402 -114.35207 90)
		(property "Reference" "C928"
			(at 0 0 90)
			(layer "B.SilkS")
			(hide yes)
			(effects
				(font
					(size 1.27 1.27)
				)
				(justify mirror)
			)
		)
		(property "Value" ""
			(at 0 0 90)
			(layer "B.Fab")
			(effects
				(font
					(size 1.27 1.27)
				)
				(justify mirror)
			)
		)
		(duplicate_pad_numbers_are_jumpers no)
		(fp_line
			(start 0.7874 -0.4064)
			(end -0.7874 -0.4064)
			(stroke
				(width 0.1524)
				(type default)
			)
			(layer "B.SilkS")
		)
		(fp_line
			(start -0.7874 -0.4064)
			(end -0.7874 0.4064)
			(stroke
				(width 0.1524)
				(type default)
			)
			(layer "B.SilkS")
		)
		(fp_line
			(start 0.7874 0.4064)
			(end 0.7874 -0.4064)
			(stroke
				(width 0.1524)
				(type default)
			)
			(layer "B.SilkS")
		)
		(fp_line
			(start -0.7874 0.4064)
			(end 0.7874 0.4064)
			(stroke
				(width 0.1524)
				(type default)
			)
			(layer "B.SilkS")
		)
		(fp_line
			(start 0.67945 -0.305054)
			(end 0.12065 -0.305054)
			(stroke
				(width 0.1)
				(type default)
			)
			(layer "B.Fab")
		)
		(fp_line
			(start 0.12065 -0.305054)
			(end 0.12065 -0.2794)
			(stroke
				(width 0.1)
				(type default)
			)
			(layer "B.Fab")
		)
		(fp_line
			(start -0.12065 -0.3048)
			(end -0.67945 -0.3048)
			(stroke
				(width 0.1)
				(type default)
			)
			(layer "B.Fab")
		)
		(fp_line
			(start -0.67945 -0.3048)
			(end -0.67945 0.3048)
			(stroke
				(width 0.1)
				(type default)
			)
			(layer "B.Fab")
		)
		(fp_line
			(start 0.12065 -0.2794)
			(end -0.12065 -0.2794)
			(stroke
				(width 0.1)
				(type default)
			)
			(layer "B.Fab")
		)
		(fp_line
			(start -0.12065 -0.2794)
			(end -0.12065 -0.3048)
			(stroke
				(width 0.1)
				(type default)
			)
			(layer "B.Fab")
		)
		(fp_line
			(start 0.12065 0.2794)
			(end 0.12065 0.3048)
			(stroke
				(width 0.1)
				(type default)
			)
			(layer "B.Fab")
		)
		(fp_line
			(start -0.120396 0.2794)
			(end 0.12065 0.2794)
			(stroke
				(width 0.1)
				(type default)
			)
			(layer "B.Fab")
		)
		(fp_line
			(start 0.67945 0.3048)
			(end 0.67945 -0.305054)
			(stroke
				(width 0.1)
				(type default)
			)
			(layer "B.Fab")
		)
		(fp_line
			(start 0.12065 0.3048)
			(end 0.67945 0.3048)
			(stroke
				(width 0.1)
				(type default)
			)
			(layer "B.Fab")
		)
		(fp_line
			(start -0.120396 0.3048)
			(end -0.120396 0.2794)
			(stroke
				(width 0.1)
				(type default)
			)
			(layer "B.Fab")
		)
		(fp_line
			(start -0.67945 0.3048)
			(end -0.120396 0.3048)
			(stroke
				(width 0.1)
				(type default)
			)
			(layer "B.Fab")
		)
		(pad "1" smd circle
			(at 0.40005 0 270)
			(size 0 0)
			(layers "B.Cu" "B.Mask" "B.Paste")
			(net "P3V3_NIC5")
		)
		(pad "2" smd circle
			(at -0.40005 0 270)
			(size 0 0)
			(layers "B.Cu" "B.Mask" "B.Paste")
			(net "GND")
		)
	)
	(footprint ""
		(layer "B.Cu")
		(at 397.97482 -297.79976 90)
		(property "Reference" "C1902"
			(at 0 0 90)
			(layer "B.SilkS")
			(hide yes)
			(effects
				(font
					(size 1.27 1.27)
				)
				(justify mirror)
			)
		)
		(property "Value" ""
			(at 0 0 90)
			(layer "B.Fab")
			(effects
				(font
					(size 1.27 1.27)
				)
				(justify mirror)
			)
		)
		(duplicate_pad_numbers_are_jumpers no)
		(fp_line
			(start 0.299974 -0.150114)
			(end -0.299974 -0.150114)
			(stroke
				(width 0.1)
				(type default)
			)
			(layer "B.Fab")
		)
		(fp_line
			(start -0.299974 -0.150114)
			(end -0.299974 0.150114)
			(stroke
				(width 0.1)
				(type default)
			)
			(layer "B.Fab")
		)
		(fp_line
			(start 0.299974 0.150114)
			(end 0.299974 -0.150114)
			(stroke
				(width 0.1)
				(type default)
			)
			(layer "B.Fab")
		)
		(fp_line
			(start -0.299974 0.150114)
			(end 0.299974 0.150114)
			(stroke
				(width 0.1)
				(type default)
			)
			(layer "B.Fab")
		)
		(pad "1" smd rect
			(at 0.2667 0 270)
			(size 0.3048 0.381)
			(layers "B.Cu" "B.Mask" "B.Paste")
			(net "P0V8_PEX3")
		)
		(pad "2" smd rect
			(at -0.2667 0 270)
			(size 0.3048 0.381)
			(layers "B.Cu" "B.Mask" "B.Paste")
			(net "GND")
		)
	)
)
